G04 ================== begin FILE IDENTIFICATION RECORD ==================*
G04 Layout Name:  14545-sa.brd*
G04 Film Name:    DIF_REF_L6*
G04 File Format:  Gerber RS274X*
G04 File Origin:  Cadence Allegro 16.5-S056*
G04 Origin Date:  Fri Aug 01 17:59:01 2014*
G04 *
G04 Layer:  BOARD GEOMETRY/OUTLINE*
G04 Layer:  BOARD GEOMETRY/DIF_REF_L6*
G04 Layer:  BOARD GEOMETRY/PANEL_OUTLINE*
G04 *
G04 Offset:    (0.00 0.00)*
G04 Mirror:    No*
G04 Mode:      Positive*
G04 Rotation:  0*
G04 FullContactRelief:  No*
G04 UndefLineWidth:     6.00*
G04 ================== end FILE IDENTIFICATION RECORD ====================*
%FSLAX35Y35*MOIN*%
%IR0*IPPOS*OFA0.00000B0.00000*MIA0B0*SFA1.00000B1.00000*%
%ADD10C,.006*%
%ADD11C,.0045*%
G75*
%LPD*%
G75*
G54D10*
G01X-78741Y15000D02*
G03X-63741Y0I15000J0D01*
G01X-78741Y15000D02*
Y120047D01*
G01X-63741Y135047D02*
G03X-78741Y120047I0J-15000D01*
G01Y298866D02*
G03X-63741Y283866I15000J0D01*
G01X-78741Y319646D02*
Y298866D01*
G01X-63741Y334646D02*
G03X-78741Y319646I0J-15000D01*
G01Y908315D02*
G03X-63741Y893315I15000J0D01*
G01X-78741Y908315D02*
Y1104299D01*
G01X-63741Y1119299D02*
G03X-78741Y1104299I0J-15000D01*
G01Y1283118D02*
G03X-63741Y1268118I15000J0D01*
G01X-78741Y1304285D02*
Y1283118D01*
G01X-63741Y1319285D02*
G03X-78741Y1304285I0J-15000D01*
G01Y1892953D02*
G03X-63741Y1877953I15000J0D01*
G01X-78741Y1892953D02*
Y1977126D01*
G01X-63741Y1992126D02*
G03X-78741Y1977126I0J-15000D01*
G01X19882Y1197835D02*
X1969D01*
X0Y1195866D01*
Y832480D01*
X1969Y830512D01*
X19882D01*
G02Y823031I0J-3740D01*
G01X1969D01*
X0Y821063D01*
Y423031D01*
X1969Y421063D01*
X19882D01*
G02Y413583I0J-3740D01*
G01X1969D01*
X0Y411614D01*
Y223031D01*
X1969Y221063D01*
X19882D01*
G02Y213583I0J-3740D01*
G01X1969D01*
X0Y211614D01*
Y3937D01*
G03X3937Y0I3937J0D01*
G01X1029528D01*
G03X1033465Y3937I0J3937D01*
G01Y1424882D01*
X1029528Y1428819D01*
X1024213D01*
G02X1019291Y1433740I-1J4921D01*
G01Y1607933D01*
X1015354Y1611870D01*
X989744D01*
G02Y1616083I0J2107D01*
G01X1015354D01*
X1019291Y1620020D01*
Y1676496D01*
G02X1024213Y1681417I4921J0D01*
G01X1029528D01*
X1033465Y1685354D01*
Y1988189D01*
G03X1029528Y1992126I-3937J0D01*
G01X3937D01*
G03X0Y1988189I0J-3937D01*
G01Y1816732D01*
X1969Y1814764D01*
X19882D01*
G02Y1807283I0J-3740D01*
G01X1969D01*
X0Y1805315D01*
Y1407283D01*
X1969Y1405315D01*
X19882D01*
G02Y1397835I0J-3740D01*
G01X1969D01*
X0Y1395866D01*
Y1207283D01*
X1969Y1205315D01*
X19882D01*
G02Y1197835I0J-3740D01*
G01Y1197834D02*
X1969D01*
X0Y1195865D01*
Y832479D01*
X1969Y830511D01*
X19882D01*
G02Y823030I0J-3741D01*
G01X1969D01*
X0Y821062D01*
Y423030D01*
X1969Y421062D01*
X19882D01*
G02Y413582I0J-3740D01*
G01X1969D01*
X0Y411613D01*
Y223030D01*
X1969Y221062D01*
X19882D01*
G02Y213582I0J-3740D01*
G01X1969D01*
X0Y211613D01*
Y3936D01*
G03X3937Y-1I3937J0D01*
G01X1029528D01*
G03X1033465Y3936I0J3937D01*
G01Y1424881D01*
X1029528Y1428818D01*
X1024213D01*
G02X1019291Y1433739I-1J4921D01*
G01Y1607932D01*
X1015354Y1611869D01*
X989744D01*
G02Y1616082I0J2107D01*
G01X1015354D01*
X1019291Y1620019D01*
Y1676495D01*
G02X1024213Y1681416I4921J0D01*
G01X1029528D01*
X1033465Y1685353D01*
Y1988188D01*
G03X1029528Y1992125I-3937J0D01*
G01X3937D01*
G03X0Y1988188I0J-3937D01*
G01Y1816731D01*
X1969Y1814763D01*
X19882D01*
G02Y1807282I0J-3741D01*
G01X1969D01*
X0Y1805314D01*
Y1407282D01*
X1969Y1405314D01*
X19882D01*
G02Y1397834I0J-3740D01*
G01X1969D01*
X0Y1395865D01*
Y1207282D01*
X1969Y1205314D01*
X19882D01*
G02Y1197834I0J-3740D01*
G01X-7875Y0D02*
X-63741D01*
G01X-7875Y41772D02*
Y104969D01*
G01Y17252D02*
Y0D01*
G01Y41772D02*
G03X-1I3937J-1D01*
G01Y17213D02*
G03X-7875I-3937J0D01*
G01Y41772D02*
G03X-1I3937J-1D01*
G01Y17213D02*
G03X-7875I-3937J0D01*
G01Y129516D02*
Y135047D01*
G01D02*
X-63741D01*
G01X-7875Y129516D02*
G03X-1I3937J0D01*
G01Y104958D02*
G03X-7875I-3937J0D01*
G01Y283866D02*
Y300383D01*
G01X-19814Y283866D02*
X-63741D01*
G01X-7875D02*
X-19814D01*
G01X-1Y300383D02*
G03X-7875I-3937J0D01*
G01Y331986D02*
Y324003D01*
G01Y331986D02*
Y334646D01*
G01D02*
X-63741D01*
G01X-7875Y324003D02*
G03X-1I3937J0D01*
G01X-7875Y905988D02*
Y893315D01*
G01D02*
X-63741D01*
G01X-7875Y1069005D02*
Y933234D01*
G01D02*
G03X-1I3937J0D01*
G01Y905988D02*
G03X-7875I-3937J0D01*
G01Y1108863D02*
Y1119299D01*
G01X-19126D02*
X-7875D01*
G01X-15749D02*
X-63741D01*
G01X-7875Y1106300D02*
Y1111425D01*
G01Y1106300D02*
Y1092625D01*
G01D02*
G03X-1I3937J0D01*
G01Y1069005D02*
G03X-7875I-3937J0D01*
G01X-17894Y1268118D02*
X-7875D01*
G01Y1278280D02*
Y1268118D01*
G01Y1280567D02*
Y1275992D01*
G01X-15749Y1268118D02*
X-63741D01*
G01X-7875Y1309889D02*
G03X-1I3937J0D01*
G01Y1280567D02*
G03X-7875I-3937J0D01*
G01Y1309889D02*
G03X-1I3937J0D01*
G01Y1280567D02*
G03X-7875I-3937J0D01*
G01Y1309889D02*
Y1319285D01*
G01D02*
X-63741D01*
G01X-7875Y1889223D02*
Y1877953D01*
G01D02*
X-63741D01*
G01X-7875Y1912843D02*
Y1962926D01*
G01Y1912843D02*
G03X-1I3937J0D01*
G01Y1889223D02*
G03X-7875I-3937J0D01*
G01Y1912843D02*
G03X-1I3937J0D01*
G01Y1889223D02*
G03X-7875I-3937J0D01*
G01X-1Y1962926D02*
G03X-7875I-3937J0D01*
G01X-1D02*
G03X-7875I-3937J0D01*
G01Y1986546D02*
Y1992126D01*
G01D02*
X-63741D01*
G01X-7875Y1986546D02*
G03X-1I3937J0D01*
G01X-7875D02*
G03X-1I3937J0D01*
G01X37330Y-70164D02*
Y-82164D01*
G01X35030Y-70164D02*
X39630D01*
G01X41630Y-82164D02*
Y-70164D01*
G01Y-75964D02*
X42130Y-74964D01*
X42630Y-74364D01*
X43430Y-74164D01*
X44030Y-74364D01*
X44730Y-75164D01*
X45030Y-76364D01*
Y-82164D01*
G01X49330Y-74164D02*
Y-82164D01*
G01Y-70964D02*
X49130Y-70764D01*
Y-70364D01*
X49330Y-70164D01*
X49530Y-70364D01*
Y-70764D01*
X49330Y-70964D01*
G01X53830Y-80764D02*
X54330Y-81564D01*
X55030Y-82164D01*
X55630D01*
X56230Y-81764D01*
X56630Y-81164D01*
X56830Y-80364D01*
X56730Y-79164D01*
X56330Y-78564D01*
X54530Y-77364D01*
X54130Y-75964D01*
X54330Y-74964D01*
X54730Y-74364D01*
X55330Y-74164D01*
X55930Y-74364D01*
X56530Y-74964D01*
G01X65930Y-85164D02*
X66630Y-85964D01*
X67430Y-86164D01*
X68130Y-85964D01*
X68730Y-84964D01*
X69130Y-83564D01*
Y-74164D01*
G01Y-75764D02*
X68730Y-74964D01*
X68130Y-74364D01*
X67430Y-74164D01*
X66630Y-74564D01*
X66130Y-75364D01*
X65730Y-76764D01*
X65530Y-78164D01*
X65630Y-79364D01*
X66030Y-80764D01*
X66630Y-81764D01*
X67430Y-82164D01*
X68030Y-81964D01*
X68730Y-81164D01*
X69130Y-80364D01*
G01X71830Y-76764D02*
X75030D01*
X74730Y-75364D01*
X74230Y-74564D01*
X73530Y-74164D01*
X72830Y-74364D01*
X72230Y-74964D01*
X71830Y-76364D01*
X71630Y-77564D01*
Y-78764D01*
X71830Y-79964D01*
X72330Y-81164D01*
X72930Y-81964D01*
X73630Y-82164D01*
X74330Y-81764D01*
X75030Y-80564D01*
G01X77930Y-82164D02*
Y-74164D01*
G01Y-75764D02*
X78430Y-74964D01*
X78930Y-74364D01*
X79630Y-74164D01*
X80130Y-74364D01*
X80730Y-74964D01*
G01X83530Y-82164D02*
Y-70164D01*
G01Y-76164D02*
X84030Y-74964D01*
X84630Y-74364D01*
X85230Y-74164D01*
X86130Y-74564D01*
X86730Y-75364D01*
X87130Y-76764D01*
Y-78364D01*
X86930Y-79964D01*
X86530Y-81164D01*
X85830Y-81964D01*
X85230Y-82164D01*
X84630Y-81964D01*
X84030Y-81364D01*
X83530Y-80364D01*
G01X89830Y-76764D02*
X93030D01*
X92730Y-75364D01*
X92230Y-74564D01*
X91530Y-74164D01*
X90830Y-74364D01*
X90230Y-74964D01*
X89830Y-76364D01*
X89630Y-77564D01*
Y-78764D01*
X89830Y-79964D01*
X90330Y-81164D01*
X90930Y-81964D01*
X91630Y-82164D01*
X92330Y-81764D01*
X93030Y-80564D01*
G01X95930Y-82164D02*
Y-74164D01*
G01Y-75764D02*
X96430Y-74964D01*
X96930Y-74364D01*
X97630Y-74164D01*
X98130Y-74364D01*
X98730Y-74964D01*
G01X109330Y-74164D02*
Y-82164D01*
G01Y-70964D02*
X109130Y-70764D01*
Y-70364D01*
X109330Y-70164D01*
X109530Y-70364D01*
Y-70764D01*
X109330Y-70964D01*
G01X113830Y-80764D02*
X114330Y-81564D01*
X115030Y-82164D01*
X115630D01*
X116230Y-81764D01*
X116630Y-81164D01*
X116830Y-80364D01*
X116730Y-79164D01*
X116330Y-78564D01*
X114530Y-77364D01*
X114130Y-75964D01*
X114330Y-74964D01*
X114730Y-74364D01*
X115330Y-74164D01*
X115930Y-74364D01*
X116530Y-74964D01*
G01X125730Y-85164D02*
X126430Y-85964D01*
X127030Y-86164D01*
X127830Y-85764D01*
X128430Y-84764D01*
X128730Y-82964D01*
Y-74164D01*
G01Y-70964D02*
X128530Y-70764D01*
Y-70364D01*
X128730Y-70164D01*
X128930Y-70364D01*
Y-70764D01*
X128730Y-70964D01*
G01X131630Y-74164D02*
Y-79764D01*
X132030Y-81164D01*
X132630Y-81964D01*
X133330Y-82164D01*
X134030Y-81964D01*
X134630Y-81164D01*
X135030Y-79764D01*
G01Y-82164D02*
Y-74164D01*
G01X137830Y-80764D02*
X138330Y-81564D01*
X139030Y-82164D01*
X139630D01*
X140230Y-81764D01*
X140630Y-81164D01*
X140830Y-80364D01*
X140730Y-79164D01*
X140330Y-78564D01*
X138530Y-77364D01*
X138130Y-75964D01*
X138330Y-74964D01*
X138730Y-74364D01*
X139330Y-74164D01*
X139930Y-74364D01*
X140530Y-74964D01*
G01X145330Y-70164D02*
Y-82164D01*
G01X143930Y-74164D02*
X146730D01*
G01X156730Y-82164D02*
Y-71964D01*
X156930Y-70964D01*
X157330Y-70364D01*
X157930Y-70164D01*
X158530Y-70564D01*
X158830Y-71564D01*
G01X157630Y-74964D02*
X155630D01*
G01X163330Y-82164D02*
X162730Y-81964D01*
X162130Y-81164D01*
X161730Y-79764D01*
X161530Y-78164D01*
X161730Y-76564D01*
X162130Y-75164D01*
X162730Y-74364D01*
X163330Y-74164D01*
X163930Y-74364D01*
X164530Y-75164D01*
X164930Y-76564D01*
X165030Y-78164D01*
X164930Y-79764D01*
X164530Y-81164D01*
X163930Y-81964D01*
X163330Y-82164D01*
G01X167930D02*
Y-74164D01*
G01Y-75764D02*
X168430Y-74964D01*
X168930Y-74364D01*
X169630Y-74164D01*
X170130Y-74364D01*
X170730Y-74964D01*
G01X179230Y-85764D02*
X179830Y-86164D01*
X180630Y-85764D01*
X181130Y-84964D01*
X181530Y-83964D01*
X182130Y-80764D01*
X183430Y-74164D01*
G01X180230D02*
X182130Y-80764D01*
G01X187330Y-82164D02*
X186730Y-81964D01*
X186130Y-81164D01*
X185730Y-79764D01*
X185530Y-78164D01*
X185730Y-76564D01*
X186130Y-75164D01*
X186730Y-74364D01*
X187330Y-74164D01*
X187930Y-74364D01*
X188530Y-75164D01*
X188930Y-76564D01*
X189030Y-78164D01*
X188930Y-79764D01*
X188530Y-81164D01*
X187930Y-81964D01*
X187330Y-82164D01*
G01X191630Y-74164D02*
Y-79764D01*
X192030Y-81164D01*
X192630Y-81964D01*
X193330Y-82164D01*
X194030Y-81964D01*
X194630Y-81164D01*
X195030Y-79764D01*
G01Y-82164D02*
Y-74164D01*
G01X203930Y-82164D02*
Y-74164D01*
G01Y-75764D02*
X204430Y-74964D01*
X204930Y-74364D01*
X205630Y-74164D01*
X206130Y-74364D01*
X206730Y-74964D01*
G01X209830Y-76764D02*
X213030D01*
X212730Y-75364D01*
X212230Y-74564D01*
X211530Y-74164D01*
X210830Y-74364D01*
X210230Y-74964D01*
X209830Y-76364D01*
X209630Y-77564D01*
Y-78764D01*
X209830Y-79964D01*
X210330Y-81164D01*
X210930Y-81964D01*
X211630Y-82164D01*
X212330Y-81764D01*
X213030Y-80564D01*
G01X216730Y-82164D02*
Y-71964D01*
X216930Y-70964D01*
X217330Y-70364D01*
X217930Y-70164D01*
X218530Y-70564D01*
X218830Y-71564D01*
G01X217630Y-74964D02*
X215630D01*
G01X221830Y-76764D02*
X225030D01*
X224730Y-75364D01*
X224230Y-74564D01*
X223530Y-74164D01*
X222830Y-74364D01*
X222230Y-74964D01*
X221830Y-76364D01*
X221630Y-77564D01*
Y-78764D01*
X221830Y-79964D01*
X222330Y-81164D01*
X222930Y-81964D01*
X223630Y-82164D01*
X224330Y-81764D01*
X225030Y-80564D01*
G01X227930Y-82164D02*
Y-74164D01*
G01Y-75764D02*
X228430Y-74964D01*
X228930Y-74364D01*
X229630Y-74164D01*
X230130Y-74364D01*
X230730Y-74964D01*
G01X233830Y-76764D02*
X237030D01*
X236730Y-75364D01*
X236230Y-74564D01*
X235530Y-74164D01*
X234830Y-74364D01*
X234230Y-74964D01*
X233830Y-76364D01*
X233630Y-77564D01*
Y-78764D01*
X233830Y-79964D01*
X234330Y-81164D01*
X234930Y-81964D01*
X235630Y-82164D01*
X236330Y-81764D01*
X237030Y-80564D01*
G01X239630Y-82164D02*
Y-74164D01*
G01Y-76164D02*
X240030Y-75164D01*
X240630Y-74364D01*
X241430Y-74164D01*
X242130Y-74364D01*
X242730Y-75164D01*
X243030Y-76564D01*
Y-82164D01*
G01X248930Y-75164D02*
X248230Y-74364D01*
X247630Y-74164D01*
X246830Y-74564D01*
X246230Y-75364D01*
X245830Y-76764D01*
X245730Y-78164D01*
X245830Y-79564D01*
X246230Y-80764D01*
X246830Y-81764D01*
X247630Y-82164D01*
X248330Y-81764D01*
X248930Y-80964D01*
G01X251830Y-76764D02*
X255030D01*
X254730Y-75364D01*
X254230Y-74564D01*
X253530Y-74164D01*
X252830Y-74364D01*
X252230Y-74964D01*
X251830Y-76364D01*
X251630Y-77564D01*
Y-78764D01*
X251830Y-79964D01*
X252330Y-81164D01*
X252930Y-81964D01*
X253630Y-82164D01*
X254330Y-81764D01*
X255030Y-80564D01*
G01X265330Y-70164D02*
Y-82164D01*
G01X263930Y-74164D02*
X266730D01*
G01X271330Y-82164D02*
X270730Y-81964D01*
X270130Y-81164D01*
X269730Y-79764D01*
X269530Y-78164D01*
X269730Y-76564D01*
X270130Y-75164D01*
X270730Y-74364D01*
X271330Y-74164D01*
X271930Y-74364D01*
X272530Y-75164D01*
X272930Y-76564D01*
X273030Y-78164D01*
X272930Y-79764D01*
X272530Y-81164D01*
X271930Y-81964D01*
X271330Y-82164D01*
G01X282730D02*
Y-71964D01*
X282930Y-70964D01*
X283330Y-70364D01*
X283930Y-70164D01*
X284530Y-70564D01*
X284830Y-71564D01*
G01X283630Y-74964D02*
X281630D01*
G01X289330Y-74164D02*
Y-82164D01*
G01Y-70964D02*
X289130Y-70764D01*
Y-70364D01*
X289330Y-70164D01*
X289530Y-70364D01*
Y-70764D01*
X289330Y-70964D01*
G01X293630Y-82164D02*
Y-74164D01*
G01Y-76164D02*
X294030Y-75164D01*
X294630Y-74364D01*
X295430Y-74164D01*
X296130Y-74364D01*
X296730Y-75164D01*
X297030Y-76564D01*
Y-82164D01*
G01X303130Y-70164D02*
Y-82164D01*
G01Y-80364D02*
X302730Y-81364D01*
X302130Y-81964D01*
X301430Y-82164D01*
X300630Y-81764D01*
X300030Y-80764D01*
X299630Y-79564D01*
X299530Y-78164D01*
X299630Y-76764D01*
X300030Y-75564D01*
X300630Y-74564D01*
X301430Y-74164D01*
X302130Y-74364D01*
X302630Y-74764D01*
X303130Y-75564D01*
G01X313330Y-70164D02*
Y-82164D01*
G01X311930Y-74164D02*
X314730D01*
G01X317630Y-82164D02*
Y-70164D01*
G01Y-75964D02*
X318130Y-74964D01*
X318630Y-74364D01*
X319430Y-74164D01*
X320030Y-74364D01*
X320730Y-75164D01*
X321030Y-76364D01*
Y-82164D01*
G01X323830Y-76764D02*
X327030D01*
X326730Y-75364D01*
X326230Y-74564D01*
X325530Y-74164D01*
X324830Y-74364D01*
X324230Y-74964D01*
X323830Y-76364D01*
X323630Y-77564D01*
Y-78764D01*
X323830Y-79964D01*
X324330Y-81164D01*
X324930Y-81964D01*
X325630Y-82164D01*
X326330Y-81764D01*
X327030Y-80564D01*
G01X339130Y-70164D02*
Y-82164D01*
G01Y-80364D02*
X338730Y-81364D01*
X338130Y-81964D01*
X337430Y-82164D01*
X336630Y-81764D01*
X336030Y-80764D01*
X335630Y-79564D01*
X335530Y-78164D01*
X335630Y-76764D01*
X336030Y-75564D01*
X336630Y-74564D01*
X337430Y-74164D01*
X338130Y-74364D01*
X338630Y-74764D01*
X339130Y-75564D01*
G01X343330Y-74164D02*
Y-82164D01*
G01Y-70964D02*
X343130Y-70764D01*
Y-70364D01*
X343330Y-70164D01*
X343530Y-70364D01*
Y-70764D01*
X343330Y-70964D01*
G01X348730Y-82164D02*
Y-71964D01*
X348930Y-70964D01*
X349330Y-70364D01*
X349930Y-70164D01*
X350530Y-70564D01*
X350830Y-71564D01*
G01X349630Y-74964D02*
X347630D01*
G01X354730Y-82164D02*
Y-71964D01*
X354930Y-70964D01*
X355330Y-70364D01*
X355930Y-70164D01*
X356530Y-70564D01*
X356830Y-71564D01*
G01X355630Y-74964D02*
X353630D01*
G01X359830Y-76764D02*
X363030D01*
X362730Y-75364D01*
X362230Y-74564D01*
X361530Y-74164D01*
X360830Y-74364D01*
X360230Y-74964D01*
X359830Y-76364D01*
X359630Y-77564D01*
Y-78764D01*
X359830Y-79964D01*
X360330Y-81164D01*
X360930Y-81964D01*
X361630Y-82164D01*
X362330Y-81764D01*
X363030Y-80564D01*
G01X365930Y-82164D02*
Y-74164D01*
G01Y-75764D02*
X366430Y-74964D01*
X366930Y-74364D01*
X367630Y-74164D01*
X368130Y-74364D01*
X368730Y-74964D01*
G01X371830Y-76764D02*
X375030D01*
X374730Y-75364D01*
X374230Y-74564D01*
X373530Y-74164D01*
X372830Y-74364D01*
X372230Y-74964D01*
X371830Y-76364D01*
X371630Y-77564D01*
Y-78764D01*
X371830Y-79964D01*
X372330Y-81164D01*
X372930Y-81964D01*
X373630Y-82164D01*
X374330Y-81764D01*
X375030Y-80564D01*
G01X377630Y-82164D02*
Y-74164D01*
G01Y-76164D02*
X378030Y-75164D01*
X378630Y-74364D01*
X379430Y-74164D01*
X380130Y-74364D01*
X380730Y-75164D01*
X381030Y-76564D01*
Y-82164D01*
G01X385330Y-70164D02*
Y-82164D01*
G01X383930Y-74164D02*
X386730D01*
G01X391330D02*
Y-82164D01*
G01Y-70964D02*
X391130Y-70764D01*
Y-70364D01*
X391330Y-70164D01*
X391530Y-70364D01*
Y-70764D01*
X391330Y-70964D01*
G01X399130Y-82164D02*
Y-74164D01*
G01Y-75564D02*
X398730Y-74764D01*
X398130Y-74364D01*
X397430Y-74164D01*
X396730Y-74564D01*
X396130Y-75364D01*
X395730Y-76564D01*
X395530Y-78164D01*
X395730Y-79764D01*
X396130Y-80964D01*
X396730Y-81764D01*
X397430Y-82164D01*
X398130Y-81964D01*
X398730Y-81364D01*
X399130Y-80564D01*
G01X403330Y-82164D02*
Y-70164D01*
G01X415330D02*
Y-82164D01*
G01X413930Y-74164D02*
X416730D01*
G01X419930Y-82164D02*
Y-74164D01*
G01Y-75764D02*
X420430Y-74964D01*
X420930Y-74364D01*
X421630Y-74164D01*
X422130Y-74364D01*
X422730Y-74964D01*
G01X429130Y-82164D02*
Y-74164D01*
G01Y-75564D02*
X428730Y-74764D01*
X428130Y-74364D01*
X427430Y-74164D01*
X426730Y-74564D01*
X426130Y-75364D01*
X425730Y-76564D01*
X425530Y-78164D01*
X425730Y-79764D01*
X426130Y-80964D01*
X426730Y-81764D01*
X427430Y-82164D01*
X428130Y-81964D01*
X428730Y-81364D01*
X429130Y-80564D01*
G01X434930Y-75164D02*
X434230Y-74364D01*
X433630Y-74164D01*
X432830Y-74564D01*
X432230Y-75364D01*
X431830Y-76764D01*
X431730Y-78164D01*
X431830Y-79564D01*
X432230Y-80764D01*
X432830Y-81764D01*
X433630Y-82164D01*
X434330Y-81764D01*
X434930Y-80964D01*
G01X437830Y-76764D02*
X441030D01*
X440730Y-75364D01*
X440230Y-74564D01*
X439530Y-74164D01*
X438830Y-74364D01*
X438230Y-74964D01*
X437830Y-76364D01*
X437630Y-77564D01*
Y-78764D01*
X437830Y-79964D01*
X438330Y-81164D01*
X438930Y-81964D01*
X439630Y-82164D01*
X440330Y-81764D01*
X441030Y-80564D01*
G01X443830Y-80764D02*
X444330Y-81564D01*
X445030Y-82164D01*
X445630D01*
X446230Y-81764D01*
X446630Y-81164D01*
X446830Y-80364D01*
X446730Y-79164D01*
X446330Y-78564D01*
X444530Y-77364D01*
X444130Y-75964D01*
X444330Y-74964D01*
X444730Y-74364D01*
X445330Y-74164D01*
X445930Y-74364D01*
X446530Y-74964D01*
G01X457330Y-74164D02*
Y-82164D01*
G01Y-70964D02*
X457130Y-70764D01*
Y-70364D01*
X457330Y-70164D01*
X457530Y-70364D01*
Y-70764D01*
X457330Y-70964D01*
G01X461630Y-82164D02*
Y-74164D01*
G01Y-76164D02*
X462030Y-75164D01*
X462630Y-74364D01*
X463430Y-74164D01*
X464130Y-74364D01*
X464730Y-75164D01*
X465030Y-76564D01*
Y-82164D01*
G01X475330D02*
Y-70164D01*
G01X483130Y-82164D02*
Y-74164D01*
G01Y-75564D02*
X482730Y-74764D01*
X482130Y-74364D01*
X481430Y-74164D01*
X480730Y-74564D01*
X480130Y-75364D01*
X479730Y-76564D01*
X479530Y-78164D01*
X479730Y-79764D01*
X480130Y-80964D01*
X480730Y-81764D01*
X481430Y-82164D01*
X482130Y-81964D01*
X482730Y-81364D01*
X483130Y-80564D01*
G01X485230Y-85764D02*
X485830Y-86164D01*
X486630Y-85764D01*
X487130Y-84964D01*
X487530Y-83964D01*
X488130Y-80764D01*
X489430Y-74164D01*
G01X486230D02*
X488130Y-80764D01*
G01X491830Y-76764D02*
X495030D01*
X494730Y-75364D01*
X494230Y-74564D01*
X493530Y-74164D01*
X492830Y-74364D01*
X492230Y-74964D01*
X491830Y-76364D01*
X491630Y-77564D01*
Y-78764D01*
X491830Y-79964D01*
X492330Y-81164D01*
X492930Y-81964D01*
X493630Y-82164D01*
X494330Y-81764D01*
X495030Y-80564D01*
G01X497930Y-82164D02*
Y-74164D01*
G01Y-75764D02*
X498430Y-74964D01*
X498930Y-74364D01*
X499630Y-74164D01*
X500130Y-74364D01*
X500730Y-74964D01*
G01X509330Y-70164D02*
Y-82164D01*
X513330D01*
G01X515430Y-77164D02*
X516130Y-75764D01*
X516730Y-74964D01*
X517530Y-74564D01*
X518230Y-74964D01*
X518730Y-75764D01*
X519130Y-76964D01*
X519230Y-78364D01*
X519130Y-79564D01*
X518730Y-80764D01*
X518130Y-81764D01*
X517430Y-82164D01*
X516630Y-81764D01*
X515930Y-80564D01*
X515530Y-78764D01*
X515430Y-76764D01*
X515630Y-74164D01*
X515930Y-72764D01*
X516430Y-71364D01*
X517130Y-70364D01*
X517830Y-70164D01*
X518530Y-70564D01*
X519030Y-71564D01*
G01X1041337Y24677D02*
Y0D01*
G01Y217343D02*
Y48297D01*
G01Y0D02*
X1097204D01*
G01X1033463Y48297D02*
G03X1041337I3937J0D01*
G01Y24677D02*
G03X1033463I-3937J0D01*
G01Y48297D02*
G03X1041337I3937J0D01*
G01Y24677D02*
G03X1033463I-3937J0D01*
G01X1041337Y217343D02*
G03X1033463I-3937J0D01*
G01X1041337D02*
G03X1033463I-3937J0D01*
G01X1041337Y445039D02*
Y240963D01*
G01X1033463D02*
G03X1041337I3937J0D01*
G01X1033463D02*
G03X1041337I3937J0D01*
G01Y697474D02*
Y468601D01*
G01X1033463Y468659D02*
G03X1041337I3937J0D01*
G01Y445039D02*
G03X1033463I-3937J0D01*
G01Y468659D02*
G03X1041337I3937J0D01*
G01Y445039D02*
G03X1033463I-3937J0D01*
G01X1041337Y996851D02*
Y721093D01*
G01X1033463D02*
G03X1041337I3937J0D01*
G01Y697474D02*
G03X1033463I-3937J-1D01*
G01Y721093D02*
G03X1041337I3937J0D01*
G01Y697474D02*
G03X1033463I-3937J-1D01*
G01X1041337Y1344059D02*
Y1020472D01*
G01X1033463D02*
G03X1041337I3937J0D01*
G01Y996851D02*
G03X1033463I-3937J1D01*
G01Y1020472D02*
G03X1041337I3937J0D01*
G01Y996851D02*
G03X1033463I-3937J1D01*
G01X1041337Y1367679D02*
Y1393701D01*
G01X1033463Y1367679D02*
G03X1041337I3937J0D01*
G01Y1344059D02*
G03X1033463I-3937J0D01*
G01Y1367679D02*
G03X1041337I3937J0D01*
G01Y1344059D02*
G03X1033463I-3937J0D01*
G01X1041337Y1393701D02*
X1097204D01*
G01X1041337Y1733129D02*
Y1716535D01*
G01X1065042D02*
X1041337D01*
G01X1056337D02*
X1097204D01*
G01X1041337Y1739719D02*
Y1731535D01*
G01Y1959242D02*
Y1763311D01*
G01X1033463Y1763339D02*
G03X1041337I3937J0D01*
G01Y1739719D02*
G03X1033463I-3937J0D01*
G01Y1763339D02*
G03X1041337I3937J0D01*
G01Y1739719D02*
G03X1033463I-3937J0D01*
G01X1041337Y1959242D02*
G03X1033463I-3937J0D01*
G01X1041337D02*
G03X1033463I-3937J0D01*
G01X1041337Y1992126D02*
X1097204D01*
G01X1041337Y1982862D02*
Y1992126D01*
G01X1033463Y1982862D02*
G03X1041337I3937J0D01*
G01X1033463D02*
G03X1041337I3937J0D01*
G01X1112204Y648419D02*
Y15000D01*
G01X1097204Y0D02*
G03X1112204Y15000I0J15000D01*
G01Y656293D02*
G03Y648419I0J-3937D01*
G01Y1378701D02*
Y656293D01*
G01Y1378701D02*
G03X1097204Y1393701I-15000J0D01*
G01Y1716535D02*
G03X1112204Y1731535I0J15000D01*
G01Y1977126D02*
Y1731535D01*
G01Y1977126D02*
G03X1097204Y1992126I-15000J0D01*
G54D11*
G01X129824Y532276D02*
X71499Y473950D01*
G01D02*
G02X69344Y473057I-2155J2154D01*
G01D02*
X66514D01*
G01D02*
G02X65271Y473572I1J1759D01*
G01D02*
X64397Y474446D01*
G01X64403Y471046D02*
G02X66361Y471857I1958J-1958D01*
G01D02*
X69345D01*
G01D02*
G03X72348Y473101I0J4247D01*
G01D02*
X130673Y531427D01*
G01X59999Y537550D02*
X60504Y537044D01*
G01D02*
G03X62099Y536384I1594J1595D01*
G01D02*
X69999D01*
G01D02*
G02X73181Y535066I0J-4500D01*
G01D02*
X81307Y526940D01*
G01D02*
G03X83456Y526050I2149J2149D01*
G01D02*
X87099D01*
G01D02*
G03X88298Y526546I1J1695D01*
G01D02*
X88800Y527049D01*
G01D02*
X89900Y528149D01*
G01D02*
G03X90299Y529112I-963J963D01*
G01D02*
Y532943D01*
G01D02*
G03X90153Y533296I-500J0D01*
G01D02*
X89845Y533604D01*
G01D02*
G03X89492Y533750I-353J-354D01*
G01D02*
X87023D01*
G01D02*
G03X86299Y533450I0J-1024D01*
G01D02*
X86199Y533350D01*
G01D02*
G03Y532250I550J-550D01*
G01X60003Y534150D02*
X60074Y534221D01*
G01D02*
G02X62399Y535184I2325J-2325D01*
G01D02*
X70044D01*
G01D02*
G02X72299Y534250I0J-3189D01*
G01D02*
X80457Y526092D01*
G01D02*
G03X83455Y524850I2998J2997D01*
G01D02*
X87099D01*
G01D02*
Y524851D01*
G01D02*
G03X89148Y525697I4J2896D01*
G01D02*
X89650Y526201D01*
G01D02*
X90749Y527300D01*
G01D02*
G03X91499Y529111I-1812J1811D01*
G01D02*
Y532943D01*
G01D02*
G03X91003Y534145I-1700J2D01*
G01D02*
X90694Y534454D01*
G01D02*
G03X89492Y534950I-1200J-1204D01*
G01D02*
X87594D01*
G01D02*
G02X87047Y535176I-1J773D01*
G01D02*
X86199Y536025D01*
G01X64700Y489700D02*
G03X67102Y488705I2402J2402D01*
G01D02*
X78819D01*
G01D02*
G03X81523Y489825I0J3824D01*
G01D02*
X110773Y519075D01*
G01X64600Y486300D02*
G02X67509Y487505I2909J-2909D01*
G01D02*
X78819D01*
G01D02*
G03X82372Y488976I1J5024D01*
G01D02*
X111622Y518226D01*
G01X50300Y699200D02*
G03X52953Y698101I2653J2653D01*
G01D02*
X64429D01*
G01D02*
G03X69004Y699996I0J6470D01*
G01D02*
X82408Y713400D01*
G01D02*
G03X83899Y717000I-3601J3600D01*
G01D02*
Y924181D01*
G01X50410Y695801D02*
G02X53066Y696901I2656J-2656D01*
G01D02*
X64428D01*
G01D02*
G03X69852Y699148I0J7670D01*
G01D02*
X69853Y699147D01*
G01D02*
X83257Y712551D01*
G01D02*
G03X85099Y716999I-4450J4448D01*
G01D02*
Y924180D01*
G01X83899Y924181D02*
G03X82400Y927800I-5118J0D01*
G01D02*
X80900Y929300D01*
G01D02*
X80901Y929301D01*
G01D02*
G02X79400Y932924I3622J3623D01*
G01D02*
Y939901D01*
G01D02*
G02X80742Y943142I4585J0D01*
G01D02*
X82950Y945350D01*
G01D02*
G03X83700Y947161I-1811J1811D01*
G01D02*
Y971501D01*
G01D02*
G02X85688Y976301I6789J0D01*
G01D02*
X95743Y986356D01*
G01X85099Y924180D02*
G03X83248Y928648I-6318J0D01*
G01D02*
X83249Y928649D01*
G01D02*
X81749Y930149D01*
G01D02*
G02X80600Y932923I2774J2774D01*
G01D02*
Y939900D01*
G01D02*
G02X81591Y942293I3385J0D01*
G01D02*
X83799Y944501D01*
G01D02*
X83798Y944502D01*
G01D02*
G03X84900Y947162I-2659J2660D01*
G01D02*
Y971500D01*
G01D02*
G02X86537Y975452I5589J0D01*
G01D02*
X96592Y985507D01*
G01X41500Y1724001D02*
G03X42913Y1720587I4826J-2D01*
G01D02*
X44250Y1719250D01*
G01D02*
X44251Y1719251D01*
G01D02*
G03X47751Y1717800I3502J3501D01*
G01D02*
X67042D01*
G01D02*
G03X71749Y1719751I-2J6659D01*
G01D02*
X71750Y1719750D01*
G01D02*
X76050Y1724050D01*
G01X42700Y1724000D02*
G03X43762Y1721436I3626J0D01*
G01D02*
X45099Y1720099D01*
G01D02*
G03X47752Y1719000I2653J2653D01*
G01D02*
X67041D01*
G01D02*
G03X70901Y1720599I0J5459D01*
G01D02*
X75201Y1724899D01*
G01X43600Y1737100D02*
X43628Y1737072D01*
G01D02*
G02X44300Y1735450I-1622J-1622D01*
G01D02*
Y1733476D01*
G01D02*
X44299Y1733477D01*
G01D02*
G02X44174Y1733174I-428J-1D01*
G01D02*
X43250Y1732250D01*
G01D02*
X43251Y1732249D01*
G01D02*
G03X41500Y1728025I4225J-4226D01*
G01D02*
Y1724001D01*
G01X76050Y1724050D02*
G02X81000Y1726100I4950J-4951D01*
G01D02*
X121077D01*
G01X47000Y1737100D02*
X46278Y1736378D01*
G01D02*
G03X45500Y1734500I1878J-1878D01*
G01D02*
Y1733477D01*
G01D02*
G02X45023Y1732325I-1629J0D01*
G01D02*
X44099Y1731401D01*
G01D02*
G03X42700Y1728024I3377J-3377D01*
G01D02*
Y1724000D01*
G01X75201Y1724899D02*
G02X81001Y1727300I5798J-5800D01*
G01D02*
X121078D01*
G01X95342Y1731600D02*
G03X94602Y1731230I8J-940D01*
G01D02*
G02X93862Y1730860I-747J570D01*
G01D02*
X92512D01*
G01D02*
G02X91772Y1731230I8J940D01*
G01D02*
G03X91032Y1731600I-747J-570D01*
G01D02*
X89682D01*
G01D02*
G03X88942Y1731230I8J-940D01*
G01D02*
G02X88202Y1730860I-747J570D01*
G01D02*
X86852D01*
G01D02*
G02X86112Y1731230I8J940D01*
G01D02*
G03X85372Y1731600I-747J-570D01*
G01D02*
X84022D01*
G01D02*
G03X83282Y1731230I8J-940D01*
G01D02*
G02X82542Y1730860I-747J570D01*
G01D02*
X81192D01*
G01D02*
G02X80452Y1731230I8J940D01*
G01D02*
G03X79712Y1731600I-747J-570D01*
G01D02*
X77500D01*
G01D02*
G03X72550Y1729550I0J-7001D01*
G01D02*
X71000Y1728000D01*
G01D02*
G02X66292Y1726050I-4708J4708D01*
G01D02*
X48839D01*
G01D02*
G03X45877Y1724823I0J-4189D01*
G01Y1728477D02*
G03X48839Y1727250I2962J2962D01*
G01D02*
X66293D01*
G01D02*
G03X70152Y1728848I0J5458D01*
G01D02*
X70151Y1728849D01*
G01D02*
X71701Y1730399D01*
G01D02*
G02X77501Y1732800I5798J-5800D01*
G01D02*
X110085D01*
G01X110773Y519075D02*
G03X111623Y521127I-2052J2052D01*
G01D02*
Y625569D01*
G01X111622Y518226D02*
G03X112823Y521126I-2901J2900D01*
G01D02*
Y625569D01*
G01X134599Y582396D02*
Y541100D01*
G01D02*
G02X131736Y534188I-9775J0D01*
G01D02*
X129824Y532276D01*
G01X130673Y531427D02*
X132585Y533339D01*
G01D02*
G03X135799Y541100I-7761J7760D01*
G01D02*
Y582395D01*
G01X111623Y625569D02*
G02X113250Y629499I5557J1D01*
G01D02*
X120098Y636347D01*
G01D02*
X120312Y636562D01*
G01D02*
G02X122699Y637549I2384J-2386D01*
G01D02*
Y637550D01*
G01D02*
X123799D01*
G01D02*
G03X124311Y637762I0J724D01*
G01D02*
X125499Y638950D01*
G01X112823Y625569D02*
G02X114099Y628650I4357J0D01*
G01D02*
X120949Y635500D01*
G01D02*
X121162Y635714D01*
G01D02*
G02X122699Y636350I1536J-1537D01*
G01D02*
X123799D01*
G01D02*
G02X125336Y635714I1J-2173D01*
G01D02*
X125499Y635550D01*
G01X137999Y646550D02*
X133399Y641950D01*
G01D02*
G03X132399Y639534I2416J-2415D01*
G01D02*
Y630665D01*
G01D02*
G02X131750Y629099I-2214J0D01*
G01D02*
G02X130667Y628650I-1083J1082D01*
G01D02*
X123449D01*
G01D02*
G03X121150Y627699I-2J-3249D01*
G01D02*
G03X119299Y623230I4470J-4469D01*
G01D02*
Y588150D01*
G01D02*
G03X123099Y584350I3800J0D01*
G01D02*
X130593D01*
G01D02*
G02X134451Y582751I-2J-5458D01*
G01D02*
G02X134598Y582395I-356J-356D01*
G01D02*
X134599Y582396D01*
G01X135799Y582395D02*
G03X135300Y583600I-1704J0D01*
G01D02*
G03X130592Y585550I-4708J-4708D01*
G01D02*
X123099D01*
G01D02*
G02X120499Y588150I0J2600D01*
G01D02*
Y611206D01*
G01D02*
G02X120869Y611946I940J-7D01*
G01D02*
G03X121239Y612686I-570J747D01*
G01D02*
Y614036D01*
G01D02*
G03X120869Y614776I-940J-7D01*
G01D02*
G02X120499Y615516I570J747D01*
G01D02*
Y616866D01*
G01D02*
G02X120869Y617606I940J-8D01*
G01D02*
G03X121239Y618346I-570J747D01*
G01D02*
Y619696D01*
G01D02*
G03X120869Y620436I-940J-8D01*
G01D02*
G02X120499Y621176I570J747D01*
G01D02*
Y623229D01*
G01D02*
G02X121999Y626850I5121J0D01*
G01D02*
G02X123448Y627450I1449J-1449D01*
G01D02*
X130668D01*
G01D02*
G03X132599Y628250I0J2731D01*
G01D02*
G03X133599Y630664I-2414J2414D01*
G01D02*
Y639534D01*
G01D02*
G02X134248Y641101I2216J0D01*
G01D02*
X138848Y645701D01*
G01D02*
G02X140415Y646350I1567J-1567D01*
G01D02*
X143244D01*
G01D02*
G02X144238Y645356I0J-994D01*
G01Y649131D02*
G02X142657Y647550I-1581J0D01*
G01D02*
X140415D01*
G01D02*
G03X137999Y646550I-1J-3416D01*
G01X95743Y986356D02*
G03X97250Y989994I-3638J3638D01*
G01D02*
Y1054126D01*
G01D02*
G02X98751Y1057749I5123J0D01*
G01D02*
X98750Y1057750D01*
G01D02*
X120011Y1079011D01*
G01X96592Y985507D02*
X96591Y985508D01*
G01D02*
G03X98450Y989993I-4486J4487D01*
G01D02*
Y1054127D01*
G01D02*
G02X99599Y1056901I3923J0D01*
G01D02*
X120860Y1078162D01*
G01X137477Y1081177D02*
G03X140393Y1079969I2916J2916D01*
G01D02*
X146000D01*
G01D02*
G03X149361Y1081361I0J4754D01*
G01D02*
X187450Y1119450D01*
G01X188299Y1118601D02*
X150210Y1080512D01*
G01D02*
G02X146001Y1078769I-4209J4211D01*
G01D02*
X140407D01*
G01D02*
G03X137481Y1077557I0J-4138D01*
G01X120011Y1079011D02*
G02X122399Y1080000I2388J-2389D01*
G01D02*
X122400D01*
G01D02*
G03X123844Y1080598I0J2042D01*
G01D02*
X124423Y1081177D01*
G01X120860Y1078162D02*
G02X122400Y1078800I1540J-1540D01*
G01D02*
G02X123673Y1078272I-1J-1801D01*
G01D02*
X124423Y1077523D01*
G01X134149Y1412933D02*
Y1352500D01*
G01D02*
G02X132487Y1348487I-5676J0D01*
G01D02*
X132000Y1348000D01*
G01D02*
G02X129410Y1346927I-2590J2590D01*
G01D02*
X116462D01*
G01D02*
G02X113500Y1348154I0J4189D01*
G01X135349Y1556000D02*
Y1352499D01*
G01D02*
G02X133336Y1347638I-6876J0D01*
G01D02*
X132849Y1347151D01*
G01D02*
G02X129411Y1345727I-3438J3439D01*
G01D02*
X116462D01*
G01D02*
G03X113500Y1344500I0J-4189D01*
G01X134149Y1511890D02*
Y1439883D01*
G01D02*
G02X133779Y1439143I-940J7D01*
G01D02*
G03X133409Y1438403I570J-748D01*
G01D02*
Y1437053D01*
G01D02*
G03X133779Y1436313I940J7D01*
G01D02*
G02X134149Y1435573I-570J-748D01*
G01D02*
Y1434223D01*
G01D02*
G02X133779Y1433483I-940J7D01*
G01D02*
G03X133409Y1432743I570J-748D01*
G01D02*
Y1431393D01*
G01D02*
G03X133779Y1430653I940J7D01*
G01D02*
G02X134149Y1429913I-570J-748D01*
G01D02*
Y1428563D01*
G01D02*
G02X133779Y1427823I-940J7D01*
G01D02*
G03X133409Y1427083I570J-748D01*
G01D02*
Y1425733D01*
G01D02*
G03X133779Y1424993I940J7D01*
G01D02*
G02X134149Y1424253I-570J-748D01*
G01D02*
Y1422903D01*
G01D02*
G02X133779Y1422163I-940J7D01*
G01D02*
G03X133409Y1421423I570J-748D01*
G01D02*
Y1420073D01*
G01D02*
G03X133779Y1419333I940J7D01*
G01D02*
G02X134149Y1418593I-570J-748D01*
G01D02*
Y1417243D01*
G01D02*
G02X133779Y1416503I-940J7D01*
G01D02*
G03X133409Y1415763I570J-748D01*
G01D02*
Y1414413D01*
G01D02*
G03X133779Y1413673I940J7D01*
G01D02*
G02X134149Y1412933I-570J-748D01*
G01X137435Y1563935D02*
G03X134149Y1555999I7935J-7934D01*
G01D02*
Y1538840D01*
G01D02*
G02X133779Y1538100I-940J7D01*
G01D02*
G03X133409Y1537360I570J-747D01*
G01D02*
Y1536010D01*
G01D02*
G03X133779Y1535270I940J7D01*
G01D02*
G02X134149Y1534530I-570J-747D01*
G01D02*
Y1533180D01*
G01D02*
G02X133779Y1532440I-940J7D01*
G01D02*
G03X133409Y1531700I570J-747D01*
G01D02*
Y1530350D01*
G01D02*
G03X133779Y1529610I940J7D01*
G01D02*
G02X134149Y1528870I-570J-747D01*
G01D02*
Y1527520D01*
G01D02*
G02X133779Y1526780I-940J7D01*
G01D02*
G03X133409Y1526040I570J-747D01*
G01D02*
Y1524690D01*
G01D02*
G03X133779Y1523950I940J7D01*
G01D02*
G02X134149Y1523210I-570J-747D01*
G01D02*
Y1521860D01*
G01D02*
G02X133779Y1521120I-940J7D01*
G01D02*
G03X133409Y1520380I570J-747D01*
G01D02*
Y1519030D01*
G01D02*
G03X133779Y1518290I940J7D01*
G01D02*
G02X134149Y1517550I-570J-747D01*
G01D02*
Y1516200D01*
G01D02*
G02X133779Y1515460I-940J7D01*
G01D02*
G03X133409Y1514720I570J-747D01*
G01D02*
Y1513370D01*
G01D02*
G03X133779Y1512630I940J7D01*
G01D02*
G02X134149Y1511890I-570J-747D01*
G01X138284Y1563086D02*
G03X135349Y1556000I7086J-7086D01*
G01X167000Y1651172D02*
Y1597500D01*
G01D02*
G02X164172Y1590672I-9657J0D01*
G01D02*
X137435Y1563935D01*
G01X168200Y1651173D02*
Y1597499D01*
G01D02*
G02X165021Y1589823I-10857J0D01*
G01D02*
X138284Y1563086D01*
G01X126750Y1723750D02*
X143666Y1706834D01*
G01D02*
G02X146000Y1701199I-5635J-5635D01*
G01D02*
Y1678185D01*
G01D02*
G03X148251Y1672751I7684J0D01*
G01D02*
X148250Y1672750D01*
G01D02*
X165000Y1656000D01*
G01D02*
G02X167000Y1651172I-4828J-4828D01*
G01X127599Y1724599D02*
X144515Y1707683D01*
G01D02*
G02X147200Y1701198I-6484J-6483D01*
G01D02*
Y1678184D01*
G01D02*
G03X149099Y1673599I6484J0D01*
G01D02*
X165849Y1656849D01*
G01D02*
X165848Y1656848D01*
G01D02*
G02X168200Y1651173I-5676J-5677D01*
G01X121077Y1726100D02*
G02X126750Y1723750I0J-8023D01*
G01X121078Y1727300D02*
G02X127598Y1724598I-2J-9223D01*
G01D02*
X127599Y1724599D01*
G01X183442Y1740499D02*
X122307D01*
G01D02*
G03X119403Y1739296I0J-4107D01*
G01D02*
X112853Y1732746D01*
G01D02*
X112852Y1732747D01*
G01D02*
G02X110086Y1731600I-2768J2767D01*
G01D02*
X101002D01*
G01D02*
G03X100262Y1731230I8J-940D01*
G01D02*
G02X99522Y1730860I-747J570D01*
G01D02*
X98172D01*
G01D02*
G02X97432Y1731230I8J940D01*
G01D02*
G03X96692Y1731600I-747J-570D01*
G01D02*
X95342D01*
G01X110085Y1732800D02*
G03X112004Y1733595I0J2714D01*
G01D02*
X118554Y1740145D01*
G01D02*
X118555Y1740144D01*
G01D02*
G02X122306Y1741699I3753J-3752D01*
G01D02*
X183443D01*
G01X187450Y1119450D02*
G03X189074Y1123371I-3921J3921D01*
G01D02*
Y1561401D01*
G01X190274Y1734902D02*
Y1123372D01*
G01D02*
G02X188298Y1118602I-6745J0D01*
G01D02*
X188299Y1118601D01*
G01X189074Y1561401D02*
G03X188704Y1562141I-940J-8D01*
G01D02*
G02X188334Y1562881I570J747D01*
G01D02*
Y1564231D01*
G01D02*
G02X188704Y1564971I940J-8D01*
G01D02*
G03X189074Y1565711I-570J747D01*
G01D02*
Y1581048D01*
G01D02*
G03X188704Y1581788I-940J-8D01*
G01D02*
G02X188334Y1582528I570J747D01*
G01D02*
Y1583878D01*
G01D02*
G02X188704Y1584618I940J-8D01*
G01D02*
G03X189074Y1585358I-570J747D01*
G01D02*
Y1586708D01*
G01D02*
G03X188704Y1587448I-940J-8D01*
G01D02*
G02X188334Y1588188I570J747D01*
G01D02*
Y1589538D01*
G01D02*
G02X188704Y1590278I940J-8D01*
G01D02*
G03X189074Y1591018I-570J747D01*
G01D02*
Y1592368D01*
G01D02*
G03X188704Y1593108I-940J-8D01*
G01D02*
G02X188334Y1593848I570J747D01*
G01D02*
Y1595198D01*
G01D02*
G02X188704Y1595938I940J-8D01*
G01D02*
G03X189074Y1596678I-570J747D01*
G01D02*
Y1598028D01*
G01D02*
G03X188704Y1598768I-940J-8D01*
G01D02*
G02X188334Y1599508I570J747D01*
G01D02*
Y1600858D01*
G01D02*
G02X188704Y1601598I940J-8D01*
G01D02*
G03X189074Y1602338I-570J747D01*
G01D02*
Y1734902D01*
G01D02*
G03X188145Y1737145I-3172J0D01*
G01D02*
X185745Y1739545D01*
G01D02*
G03X183442Y1740499I-2303J-2303D01*
G01X183443Y1741699D02*
G02X186593Y1740393I-2J-4457D01*
G01D02*
X186594Y1740394D01*
G01D02*
X188994Y1737994D01*
G01D02*
G02X190274Y1734902I-3092J-3091D01*
M02*
